(kicad_pcb
	(version 20260206)
	(generator "pcbnew")
	(generator_version "10.0")
	(general
		(thickness 1.6)
		(legacy_teardrops no)
	)
	(paper "A4")
	(title_block
		(title "9052_F0T_PDB_Converter_Brick_F_V03_1208_1600_OCP.brd")
		(comment 1 "Grand Teton / footprints 356-361 of 578")
	)
	(layers
		(0 "F.Cu" signal "TOP")
		(4 "In1.Cu" signal "GND")
		(6 "In2.Cu" signal "IN1")
		(8 "In3.Cu" signal "GND1")
		(10 "In4.Cu" signal "VCC")
		(12 "In5.Cu" signal "VCC1")
		(14 "In6.Cu" signal "GND2")
		(16 "In7.Cu" signal "IN2")
		(18 "In8.Cu" signal "GND3")
		(2 "B.Cu" signal "BOTTOM")
		(9 "F.Adhes" user "F.Adhesive")
		(11 "B.Adhes" user "B.Adhesive")
		(13 "F.Paste" user "Package Geometry/Pastemask Top")
		(15 "B.Paste" user "Package Geometry/Pastemask Bottom")
		(5 "F.SilkS" user "Ref Des/Silkscreen Top")
		(7 "B.SilkS" user "Ref Des/Silkscreen Bottom")
		(1 "F.Mask" user "Board Geometry/Soldermask Top")
		(3 "B.Mask" user "Board Geometry/Soldermask Bottom")
		(17 "Dwgs.User" user "User.Drawings")
		(19 "Cmts.User" user "User.Comments")
		(21 "Eco1.User" user "User.Eco1")
		(23 "Eco2.User" user "User.Eco2")
		(25 "Edge.Cuts" user "Board Geometry/Outline")
		(27 "Margin" user)
		(31 "F.CrtYd" user "Package Geometry/Place Bound Top")
		(29 "B.CrtYd" user "Package Geometry/Place Bound Bottom")
		(35 "F.Fab" user "Ref Des/Assembly Top")
		(33 "B.Fab" user "Ref Des/Assembly Bottom")
	)
	(footprint ""
		(layer "B.Cu")
		(at 236.982 -70.993 90)
		(property "Reference" "R69"
			(at 0 0 90)
			(layer "B.SilkS")
			(hide yes)
			(effects
				(font
					(size 1.27 1.27)
				)
				(justify mirror)
			)
		)
		(property "Value" ""
			(at 0 0 90)
			(layer "B.Fab")
			(effects
				(font
					(size 1.27 1.27)
				)
				(justify mirror)
			)
		)
		(duplicate_pad_numbers_are_jumpers no)
		(fp_line
			(start 0.7874 -0.4064)
			(end -0.7874 -0.4064)
			(stroke
				(width 0.1524)
				(type default)
			)
			(layer "B.SilkS")
		)
		(fp_line
			(start -0.7874 -0.4064)
			(end -0.7874 0.4064)
			(stroke
				(width 0.1524)
				(type default)
			)
			(layer "B.SilkS")
		)
		(fp_line
			(start 0.7874 0.4064)
			(end 0.7874 -0.4064)
			(stroke
				(width 0.1524)
				(type default)
			)
			(layer "B.SilkS")
		)
		(fp_line
			(start -0.7874 0.4064)
			(end 0.7874 0.4064)
			(stroke
				(width 0.1524)
				(type default)
			)
			(layer "B.SilkS")
		)
		(fp_line
			(start 0.67945 -0.305054)
			(end 0.12065 -0.305054)
			(stroke
				(width 0.1)
				(type default)
			)
			(layer "B.Fab")
		)
		(fp_line
			(start 0.12065 -0.305054)
			(end 0.12065 -0.2794)
			(stroke
				(width 0.1)
				(type default)
			)
			(layer "B.Fab")
		)
		(fp_line
			(start -0.12065 -0.3048)
			(end -0.67945 -0.3048)
			(stroke
				(width 0.1)
				(type default)
			)
			(layer "B.Fab")
		)
		(fp_line
			(start -0.67945 -0.3048)
			(end -0.67945 0.3048)
			(stroke
				(width 0.1)
				(type default)
			)
			(layer "B.Fab")
		)
		(fp_line
			(start 0.12065 -0.2794)
			(end -0.12065 -0.2794)
			(stroke
				(width 0.1)
				(type default)
			)
			(layer "B.Fab")
		)
		(fp_line
			(start -0.12065 -0.2794)
			(end -0.12065 -0.3048)
			(stroke
				(width 0.1)
				(type default)
			)
			(layer "B.Fab")
		)
		(fp_line
			(start 0.12065 0.2794)
			(end 0.12065 0.3048)
			(stroke
				(width 0.1)
				(type default)
			)
			(layer "B.Fab")
		)
		(fp_line
			(start -0.120396 0.2794)
			(end 0.12065 0.2794)
			(stroke
				(width 0.1)
				(type default)
			)
			(layer "B.Fab")
		)
		(fp_line
			(start 0.67945 0.3048)
			(end 0.67945 -0.305054)
			(stroke
				(width 0.1)
				(type default)
			)
			(layer "B.Fab")
		)
		(fp_line
			(start 0.12065 0.3048)
			(end 0.67945 0.3048)
			(stroke
				(width 0.1)
				(type default)
			)
			(layer "B.Fab")
		)
		(fp_line
			(start -0.120396 0.3048)
			(end -0.120396 0.2794)
			(stroke
				(width 0.1)
				(type default)
			)
			(layer "B.Fab")
		)
		(fp_line
			(start -0.67945 0.3048)
			(end -0.120396 0.3048)
			(stroke
				(width 0.1)
				(type default)
			)
			(layer "B.Fab")
		)
		(pad "1" smd circle
			(at 0.40005 0 270)
			(size 0 0)
			(layers "B.Cu" "B.Mask" "B.Paste")
			(net "RST_SMB_PDB_N")
		)
		(pad "2" smd circle
			(at -0.40005 0 270)
			(size 0 0)
			(layers "B.Cu" "B.Mask" "B.Paste")
			(net "RST_SMB_PDB_R_N")
		)
	)
	(footprint ""
		(layer "B.Cu")
		(at 38.989 -84.074)
		(property "Reference" "R79"
			(at 0 0 0)
			(layer "B.SilkS")
			(hide yes)
			(effects
				(font
					(size 1.27 1.27)
				)
				(justify mirror)
			)
		)
		(property "Value" ""
			(at 0 0 0)
			(layer "B.Fab")
			(effects
				(font
					(size 1.27 1.27)
				)
				(justify mirror)
			)
		)
		(duplicate_pad_numbers_are_jumpers no)
		(fp_line
			(start -0.7874 -0.4064)
			(end -0.7874 0.4064)
			(stroke
				(width 0.1524)
				(type default)
			)
			(layer "B.SilkS")
		)
		(fp_line
			(start -0.7874 0.4064)
			(end 0.7874 0.4064)
			(stroke
				(width 0.1524)
				(type default)
			)
			(layer "B.SilkS")
		)
		(fp_line
			(start 0.7874 -0.4064)
			(end -0.7874 -0.4064)
			(stroke
				(width 0.1524)
				(type default)
			)
			(layer "B.SilkS")
		)
		(fp_line
			(start 0.7874 0.4064)
			(end 0.7874 -0.4064)
			(stroke
				(width 0.1524)
				(type default)
			)
			(layer "B.SilkS")
		)
		(fp_line
			(start -0.67945 -0.3048)
			(end -0.67945 0.3048)
			(stroke
				(width 0.1)
				(type default)
			)
			(layer "B.Fab")
		)
		(fp_line
			(start -0.67945 0.3048)
			(end -0.120396 0.3048)
			(stroke
				(width 0.1)
				(type default)
			)
			(layer "B.Fab")
		)
		(fp_line
			(start -0.12065 -0.3048)
			(end -0.67945 -0.3048)
			(stroke
				(width 0.1)
				(type default)
			)
			(layer "B.Fab")
		)
		(fp_line
			(start -0.12065 -0.2794)
			(end -0.12065 -0.3048)
			(stroke
				(width 0.1)
				(type default)
			)
			(layer "B.Fab")
		)
		(fp_line
			(start -0.120396 0.2794)
			(end 0.12065 0.2794)
			(stroke
				(width 0.1)
				(type default)
			)
			(layer "B.Fab")
		)
		(fp_line
			(start -0.120396 0.3048)
			(end -0.120396 0.2794)
			(stroke
				(width 0.1)
				(type default)
			)
			(layer "B.Fab")
		)
		(fp_line
			(start 0.12065 -0.305054)
			(end 0.12065 -0.2794)
			(stroke
				(width 0.1)
				(type default)
			)
			(layer "B.Fab")
		)
		(fp_line
			(start 0.12065 -0.2794)
			(end -0.12065 -0.2794)
			(stroke
				(width 0.1)
				(type default)
			)
			(layer "B.Fab")
		)
		(fp_line
			(start 0.12065 0.2794)
			(end 0.12065 0.3048)
			(stroke
				(width 0.1)
				(type default)
			)
			(layer "B.Fab")
		)
		(fp_line
			(start 0.12065 0.3048)
			(end 0.67945 0.3048)
			(stroke
				(width 0.1)
				(type default)
			)
			(layer "B.Fab")
		)
		(fp_line
			(start 0.67945 -0.305054)
			(end 0.12065 -0.305054)
			(stroke
				(width 0.1)
				(type default)
			)
			(layer "B.Fab")
		)
		(fp_line
			(start 0.67945 0.3048)
			(end 0.67945 -0.305054)
			(stroke
				(width 0.1)
				(type default)
			)
			(layer "B.Fab")
		)
		(pad "1" smd circle
			(at 0.40005 0 180)
			(size 0 0)
			(layers "B.Cu" "B.Mask" "B.Paste")
			(net "SMB_P52V_HPDB_SDA")
		)
		(pad "2" smd circle
			(at -0.40005 0 180)
			(size 0 0)
			(layers "B.Cu" "B.Mask" "B.Paste")
			(net "SMB_P52V_HPDB_R_SDA")
		)
	)
	(footprint ""
		(layer "B.Cu")
		(at 269.621 -33.147)
		(property "Reference" "PR213"
			(at 0 0 0)
			(layer "B.SilkS")
			(hide yes)
			(effects
				(font
					(size 1.27 1.27)
				)
				(justify mirror)
			)
		)
		(property "Value" ""
			(at 0 0 0)
			(layer "B.Fab")
			(effects
				(font
					(size 1.27 1.27)
				)
				(justify mirror)
			)
		)
		(duplicate_pad_numbers_are_jumpers no)
		(fp_line
			(start -0.7874 -0.4064)
			(end -0.7874 0.4064)
			(stroke
				(width 0.1524)
				(type default)
			)
			(layer "B.SilkS")
		)
		(fp_line
			(start -0.7874 0.4064)
			(end 0.7874 0.4064)
			(stroke
				(width 0.1524)
				(type default)
			)
			(layer "B.SilkS")
		)
		(fp_line
			(start 0.7874 -0.4064)
			(end -0.7874 -0.4064)
			(stroke
				(width 0.1524)
				(type default)
			)
			(layer "B.SilkS")
		)
		(fp_line
			(start 0.7874 0.4064)
			(end 0.7874 -0.4064)
			(stroke
				(width 0.1524)
				(type default)
			)
			(layer "B.SilkS")
		)
		(fp_line
			(start -0.67945 -0.3048)
			(end -0.67945 0.3048)
			(stroke
				(width 0.1)
				(type default)
			)
			(layer "B.Fab")
		)
		(fp_line
			(start -0.67945 0.3048)
			(end -0.120396 0.3048)
			(stroke
				(width 0.1)
				(type default)
			)
			(layer "B.Fab")
		)
		(fp_line
			(start -0.12065 -0.3048)
			(end -0.67945 -0.3048)
			(stroke
				(width 0.1)
				(type default)
			)
			(layer "B.Fab")
		)
		(fp_line
			(start -0.12065 -0.2794)
			(end -0.12065 -0.3048)
			(stroke
				(width 0.1)
				(type default)
			)
			(layer "B.Fab")
		)
		(fp_line
			(start -0.120396 0.2794)
			(end 0.12065 0.2794)
			(stroke
				(width 0.1)
				(type default)
			)
			(layer "B.Fab")
		)
		(fp_line
			(start -0.120396 0.3048)
			(end -0.120396 0.2794)
			(stroke
				(width 0.1)
				(type default)
			)
			(layer "B.Fab")
		)
		(fp_line
			(start 0.12065 -0.305054)
			(end 0.12065 -0.2794)
			(stroke
				(width 0.1)
				(type default)
			)
			(layer "B.Fab")
		)
		(fp_line
			(start 0.12065 -0.2794)
			(end -0.12065 -0.2794)
			(stroke
				(width 0.1)
				(type default)
			)
			(layer "B.Fab")
		)
		(fp_line
			(start 0.12065 0.2794)
			(end 0.12065 0.3048)
			(stroke
				(width 0.1)
				(type default)
			)
			(layer "B.Fab")
		)
		(fp_line
			(start 0.12065 0.3048)
			(end 0.67945 0.3048)
			(stroke
				(width 0.1)
				(type default)
			)
			(layer "B.Fab")
		)
		(fp_line
			(start 0.67945 -0.305054)
			(end 0.12065 -0.305054)
			(stroke
				(width 0.1)
				(type default)
			)
			(layer "B.Fab")
		)
		(fp_line
			(start 0.67945 0.3048)
			(end 0.67945 -0.305054)
			(stroke
				(width 0.1)
				(type default)
			)
			(layer "B.Fab")
		)
		(pad "1" smd circle
			(at 0.40005 0 180)
			(size 0 0)
			(layers "B.Cu" "B.Mask" "B.Paste")
			(net "P52V_HS1_SIO")
		)
		(pad "2" smd circle
			(at -0.40005 0 180)
			(size 0 0)
			(layers "B.Cu" "B.Mask" "B.Paste")
			(net "GND_FIELD_SIGNAL")
		)
	)
	(footprint ""
		(layer "B.Cu")
		(at 147.32 -113.792)
		(property "Reference" "U23"
			(at 2.667 -2.51333 0)
			(unlocked yes)
			(layer "B.SilkS")
			(effects
				(font
					(size 0.7874 0.5842)
					(thickness 0.1524)
				)
				(justify left mirror)
			)
		)
		(property "Value" ""
			(at 0 0 0)
			(layer "B.Fab")
			(effects
				(font
					(size 1.27 1.27)
				)
				(justify mirror)
			)
		)
		(duplicate_pad_numbers_are_jumpers no)
		(fp_line
			(start -1.603248 -1.500124)
			(end -1.603248 1.500124)
			(stroke
				(width 0.1524)
				(type default)
			)
			(layer "B.SilkS")
		)
		(fp_line
			(start -1.603248 1.500124)
			(end 1.603248 1.500124)
			(stroke
				(width 0.1524)
				(type default)
			)
			(layer "B.SilkS")
		)
		(fp_line
			(start 1.603248 -1.500124)
			(end -1.603248 -1.500124)
			(stroke
				(width 0.1524)
				(type default)
			)
			(layer "B.SilkS")
		)
		(fp_line
			(start 1.603248 1.500124)
			(end 1.603248 -1.500124)
			(stroke
				(width 0.1524)
				(type default)
			)
			(layer "B.SilkS")
		)
		(fp_line
			(start -1.249934 -0.219964)
			(end -0.700024 -0.219964)
			(stroke
				(width 0.1)
				(type default)
			)
			(layer "B.Fab")
		)
		(fp_line
			(start -1.249934 0.219964)
			(end -1.249934 -0.219964)
			(stroke
				(width 0.1)
				(type default)
			)
			(layer "B.Fab")
		)
		(fp_line
			(start -0.700024 -1.500124)
			(end 0.700024 -1.500124)
			(stroke
				(width 0.1)
				(type default)
			)
			(layer "B.Fab")
		)
		(fp_line
			(start -0.700024 -0.219964)
			(end -0.700024 -1.500124)
			(stroke
				(width 0.1)
				(type default)
			)
			(layer "B.Fab")
		)
		(fp_line
			(start -0.700024 0.219964)
			(end -1.249934 0.219964)
			(stroke
				(width 0.1)
				(type default)
			)
			(layer "B.Fab")
		)
		(fp_line
			(start -0.700024 1.500124)
			(end -0.700024 0.219964)
			(stroke
				(width 0.1)
				(type default)
			)
			(layer "B.Fab")
		)
		(fp_line
			(start 0.6985 -0.729996)
			(end 0.6985 0.729996)
			(stroke
				(width 0.1)
				(type default)
			)
			(layer "B.Fab")
		)
		(fp_line
			(start 0.6985 0.729996)
			(end 1.249934 0.729996)
			(stroke
				(width 0.1)
				(type default)
			)
			(layer "B.Fab")
		)
		(fp_line
			(start 0.700024 -1.500124)
			(end 0.700024 -1.169924)
			(stroke
				(width 0.1)
				(type default)
			)
			(layer "B.Fab")
		)
		(fp_line
			(start 0.700024 -1.169924)
			(end 1.249934 -1.169924)
			(stroke
				(width 0.1)
				(type default)
			)
			(layer "B.Fab")
		)
		(fp_line
			(start 0.700024 1.169924)
			(end 0.700024 1.500124)
			(stroke
				(width 0.1)
				(type default)
			)
			(layer "B.Fab")
		)
		(fp_line
			(start 0.700024 1.500124)
			(end -0.700024 1.500124)
			(stroke
				(width 0.1)
				(type default)
			)
			(layer "B.Fab")
		)
		(fp_line
			(start 1.249934 -1.169924)
			(end 1.249934 -0.729996)
			(stroke
				(width 0.1)
				(type default)
			)
			(layer "B.Fab")
		)
		(fp_line
			(start 1.249934 -0.729996)
			(end 0.6985 -0.729996)
			(stroke
				(width 0.1)
				(type default)
			)
			(layer "B.Fab")
		)
		(fp_line
			(start 1.249934 0.729996)
			(end 1.249934 1.169924)
			(stroke
				(width 0.1)
				(type default)
			)
			(layer "B.Fab")
		)
		(fp_line
			(start 1.249934 1.169924)
			(end 0.700024 1.169924)
			(stroke
				(width 0.1)
				(type default)
			)
			(layer "B.Fab")
		)
		(fp_rect
			(start 0.700024 1.500124)
			(end -0.700024 -1.500124)
			(stroke
				(width 0)
				(type default)
			)
			(fill no)
			(layer "B.Fab")
		)
		(pad "D" smd rect
			(at -0.999998 0 270)
			(size 0.8128 0.9144)
			(layers "B.Cu" "B.Mask" "B.Paste")
			(net "BRICK_P12V0_EN_R_N")
		)
		(pad "G" smd rect
			(at 0.999998 -0.94996 270)
			(size 0.8128 0.9144)
			(layers "B.Cu" "B.Mask" "B.Paste")
			(net "PWRGD_P52V_HS1_PG")
		)
		(pad "S" smd rect
			(at 0.999998 0.94996 270)
			(size 0.8128 0.9144)
			(layers "B.Cu" "B.Mask" "B.Paste")
			(net "GND")
		)
	)
	(footprint ""
		(layer "B.Cu")
		(at 209.169 -82.55 90)
		(property "Reference" "R20"
			(at 0 0 90)
			(layer "B.SilkS")
			(hide yes)
			(effects
				(font
					(size 1.27 1.27)
				)
				(justify mirror)
			)
		)
		(property "Value" ""
			(at 0 0 90)
			(layer "B.Fab")
			(effects
				(font
					(size 1.27 1.27)
				)
				(justify mirror)
			)
		)
		(duplicate_pad_numbers_are_jumpers no)
		(fp_line
			(start 0.7874 -0.4064)
			(end -0.7874 -0.4064)
			(stroke
				(width 0.1524)
				(type default)
			)
			(layer "B.SilkS")
		)
		(fp_line
			(start -0.7874 -0.4064)
			(end -0.7874 0.4064)
			(stroke
				(width 0.1524)
				(type default)
			)
			(layer "B.SilkS")
		)
		(fp_line
			(start 0.7874 0.4064)
			(end 0.7874 -0.4064)
			(stroke
				(width 0.1524)
				(type default)
			)
			(layer "B.SilkS")
		)
		(fp_line
			(start -0.7874 0.4064)
			(end 0.7874 0.4064)
			(stroke
				(width 0.1524)
				(type default)
			)
			(layer "B.SilkS")
		)
		(fp_line
			(start 0.67945 -0.305054)
			(end 0.12065 -0.305054)
			(stroke
				(width 0.1)
				(type default)
			)
			(layer "B.Fab")
		)
		(fp_line
			(start 0.12065 -0.305054)
			(end 0.12065 -0.2794)
			(stroke
				(width 0.1)
				(type default)
			)
			(layer "B.Fab")
		)
		(fp_line
			(start -0.12065 -0.3048)
			(end -0.67945 -0.3048)
			(stroke
				(width 0.1)
				(type default)
			)
			(layer "B.Fab")
		)
		(fp_line
			(start -0.67945 -0.3048)
			(end -0.67945 0.3048)
			(stroke
				(width 0.1)
				(type default)
			)
			(layer "B.Fab")
		)
		(fp_line
			(start 0.12065 -0.2794)
			(end -0.12065 -0.2794)
			(stroke
				(width 0.1)
				(type default)
			)
			(layer "B.Fab")
		)
		(fp_line
			(start -0.12065 -0.2794)
			(end -0.12065 -0.3048)
			(stroke
				(width 0.1)
				(type default)
			)
			(layer "B.Fab")
		)
		(fp_line
			(start 0.12065 0.2794)
			(end 0.12065 0.3048)
			(stroke
				(width 0.1)
				(type default)
			)
			(layer "B.Fab")
		)
		(fp_line
			(start -0.120396 0.2794)
			(end 0.12065 0.2794)
			(stroke
				(width 0.1)
				(type default)
			)
			(layer "B.Fab")
		)
		(fp_line
			(start 0.67945 0.3048)
			(end 0.67945 -0.305054)
			(stroke
				(width 0.1)
				(type default)
			)
			(layer "B.Fab")
		)
		(fp_line
			(start 0.12065 0.3048)
			(end 0.67945 0.3048)
			(stroke
				(width 0.1)
				(type default)
			)
			(layer "B.Fab")
		)
		(fp_line
			(start -0.120396 0.3048)
			(end -0.120396 0.2794)
			(stroke
				(width 0.1)
				(type default)
			)
			(layer "B.Fab")
		)
		(fp_line
			(start -0.67945 0.3048)
			(end -0.120396 0.3048)
			(stroke
				(width 0.1)
				(type default)
			)
			(layer "B.Fab")
		)
		(pad "1" smd circle
			(at 0.40005 0 270)
			(size 0 0)
			(layers "B.Cu" "B.Mask" "B.Paste")
			(net "P3V3_AUX")
		)
		(pad "2" smd circle
			(at -0.40005 0 270)
			(size 0 0)
			(layers "B.Cu" "B.Mask" "B.Paste")
			(net "PCA9555_A2")
		)
	)
	(footprint ""
		(layer "B.Cu")
		(at 233.68 -87.884 -90)
		(property "Reference" "U9"
			(at 4.699 -0.86233 270)
			(unlocked yes)
			(layer "B.SilkS")
			(effects
				(font
					(size 0.7874 0.5842)
					(thickness 0.1524)
				)
				(justify left mirror)
			)
		)
		(property "Value" ""
			(at 0 0 90)
			(layer "B.Fab")
			(effects
				(font
					(size 1.27 1.27)
				)
				(justify mirror)
			)
		)
		(duplicate_pad_numbers_are_jumpers no)
		(fp_line
			(start -2.032 1.549908)
			(end 2.032 1.549908)
			(stroke
				(width 0.1524)
				(type default)
			)
			(layer "B.SilkS")
		)
		(fp_line
			(start 2.032 1.549908)
			(end 2.032 -1.549908)
			(stroke
				(width 0.1524)
				(type default)
			)
			(layer "B.SilkS")
		)
		(fp_line
			(start -2.032 -1.549908)
			(end -2.032 1.549908)
			(stroke
				(width 0.1524)
				(type default)
			)
			(layer "B.SilkS")
		)
		(fp_line
			(start 2.032 -1.549908)
			(end -2.032 -1.549908)
			(stroke
				(width 0.1524)
				(type default)
			)
			(layer "B.SilkS")
		)
		(fp_poly
			(pts
				(xy 2.9464 -1.2192) (xy 2.9464 -0.7112) (xy 2.1844 -0.9652)
			)
			(stroke
				(width 0)
				(type default)
			)
			(fill yes)
			(layer "B.SilkS")
		)
		(fp_line
			(start -0.849884 1.549908)
			(end -0.849884 -1.549908)
			(stroke
				(width 0.1)
				(type default)
			)
			(layer "B.Fab")
		)
		(fp_line
			(start 0.849884 1.549908)
			(end -0.849884 1.549908)
			(stroke
				(width 0.1)
				(type default)
			)
			(layer "B.Fab")
		)
		(fp_line
			(start -0.849884 -1.549908)
			(end 0.849884 -1.549908)
			(stroke
				(width 0.1)
				(type default)
			)
			(layer "B.Fab")
		)
		(fp_line
			(start 0.849884 -1.549908)
			(end 0.849884 1.549908)
			(stroke
				(width 0.1)
				(type default)
			)
			(layer "B.Fab")
		)
		(fp_poly
			(pts
				(xy 2.9464 -1.2192) (xy 2.9464 -0.7112) (xy 2.1844 -0.9652)
			)
			(stroke
				(width 0)
				(type default)
			)
			(fill yes)
			(layer "B.Fab")
		)
		(pad "1" smd rect
			(at 1.225042 -0.94996 180)
			(size 0.4572 1.3208)
			(layers "B.Cu" "B.Mask" "B.Paste")
			(net "PWRGD_P3V3_AUX_MB_BUF_N")
		)
		(pad "2" smd rect
			(at 1.225042 0 180)
			(size 0.4572 1.3208)
			(layers "B.Cu" "B.Mask" "B.Paste")
			(net "RST_SMB_PDB_N")
		)
		(pad "3" smd rect
			(at 1.225042 0.94996 180)
			(size 0.4572 1.3208)
			(layers "B.Cu" "B.Mask" "B.Paste")
			(net "GND")
		)
		(pad "4" smd rect
			(at -1.225042 0.94996 180)
			(size 0.4572 1.3208)
			(layers "B.Cu" "B.Mask" "B.Paste")
			(net "RST_SMB_PDB_BUF_R_N")
		)
		(pad "5" smd rect
			(at -1.225042 -0.94996 180)
			(size 0.4572 1.3208)
			(layers "B.Cu" "B.Mask" "B.Paste")
			(net "P3V3_AUX")
		)
	)
)
